(kicad_pcb
	(version 20260206)
	(generator "pcbnew")
	(generator_version "10.0")
	(general
		(thickness 1.6)
		(legacy_teardrops no)
	)
	(paper "A4")
	(title_block
		(title "04192023_DAF0TMB3IC0_F0TG_MB_C_brd_V02_OCP.brd")
		(comment 1 "Grand Teton / footprints 3322-3328 of 8354")
	)
	(layers
		(0 "F.Cu" signal "TOP")
		(4 "In1.Cu" signal "GND")
		(6 "In2.Cu" signal "IN1")
		(8 "In3.Cu" signal "GND1")
		(10 "In4.Cu" signal "IN2")
		(12 "In5.Cu" signal "GND2")
		(14 "In6.Cu" signal "IN3")
		(16 "In7.Cu" signal "GND3")
		(18 "In8.Cu" signal "VCC")
		(20 "In9.Cu" signal "VCC1")
		(22 "In10.Cu" signal "GND4")
		(24 "In11.Cu" signal "IN4")
		(26 "In12.Cu" signal "GND5")
		(28 "In13.Cu" signal "IN5")
		(30 "In14.Cu" signal "GND6")
		(32 "In15.Cu" signal "IN6")
		(34 "In16.Cu" signal "GND7")
		(2 "B.Cu" signal "BOTTOM")
		(9 "F.Adhes" user "F.Adhesive")
		(11 "B.Adhes" user "B.Adhesive")
		(13 "F.Paste" user "Package Geometry/Pastemask Top")
		(15 "B.Paste" user "Package Geometry/Pastemask Bottom")
		(5 "F.SilkS" user "Ref Des/Silkscreen Top")
		(7 "B.SilkS" user "Ref Des/Silkscreen Bottom")
		(1 "F.Mask" user "Board Geometry/Soldermask Top")
		(3 "B.Mask" user "Board Geometry/Soldermask Bottom")
		(17 "Dwgs.User" user "User.Drawings")
		(19 "Cmts.User" user "User.Comments")
		(21 "Eco1.User" user "User.Eco1")
		(23 "Eco2.User" user "User.Eco2")
		(25 "Edge.Cuts" user "Board Geometry/Outline")
		(27 "Margin" user)
		(31 "F.CrtYd" user "Package Geometry/Place Bound Top")
		(29 "B.CrtYd" user "Package Geometry/Place Bound Bottom")
		(35 "F.Fab" user "Ref Des/Assembly Top")
		(33 "B.Fab" user "Ref Des/Assembly Bottom")
	)
	(footprint ""
		(layer "F.Cu")
		(at 93.29801 -53.685694)
		(property "Reference" "PC2140"
			(at 0 0 0)
			(layer "F.SilkS")
			(hide yes)
			(effects
				(font
					(size 1.27 1.27)
				)
			)
		)
		(property "Value" ""
			(at 0 0 0)
			(layer "F.Fab")
			(effects
				(font
					(size 1.27 1.27)
				)
			)
		)
		(duplicate_pad_numbers_are_jumpers no)
		(fp_line
			(start -0.7874 -0.4064)
			(end 0.7874 -0.4064)
			(stroke
				(width 0.1524)
				(type default)
			)
			(layer "F.SilkS")
		)
		(fp_line
			(start -0.7874 0.4064)
			(end -0.7874 -0.4064)
			(stroke
				(width 0.1524)
				(type default)
			)
			(layer "F.SilkS")
		)
		(fp_line
			(start 0.7874 -0.4064)
			(end 0.7874 0.4064)
			(stroke
				(width 0.1524)
				(type default)
			)
			(layer "F.SilkS")
		)
		(fp_line
			(start 0.7874 0.4064)
			(end -0.7874 0.4064)
			(stroke
				(width 0.1524)
				(type default)
			)
			(layer "F.SilkS")
		)
		(fp_line
			(start -0.67945 -0.305054)
			(end -0.12065 -0.305054)
			(stroke
				(width 0.1)
				(type default)
			)
			(layer "F.Fab")
		)
		(fp_line
			(start -0.67945 0.3048)
			(end -0.67945 -0.305054)
			(stroke
				(width 0.1)
				(type default)
			)
			(layer "F.Fab")
		)
		(fp_line
			(start -0.12065 -0.305054)
			(end -0.12065 -0.2794)
			(stroke
				(width 0.1)
				(type default)
			)
			(layer "F.Fab")
		)
		(fp_line
			(start -0.12065 -0.2794)
			(end 0.12065 -0.2794)
			(stroke
				(width 0.1)
				(type default)
			)
			(layer "F.Fab")
		)
		(fp_line
			(start -0.12065 0.2794)
			(end -0.12065 0.3048)
			(stroke
				(width 0.1)
				(type default)
			)
			(layer "F.Fab")
		)
		(fp_line
			(start -0.12065 0.3048)
			(end -0.67945 0.3048)
			(stroke
				(width 0.1)
				(type default)
			)
			(layer "F.Fab")
		)
		(fp_line
			(start 0.120396 0.2794)
			(end -0.12065 0.2794)
			(stroke
				(width 0.1)
				(type default)
			)
			(layer "F.Fab")
		)
		(fp_line
			(start 0.120396 0.3048)
			(end 0.120396 0.2794)
			(stroke
				(width 0.1)
				(type default)
			)
			(layer "F.Fab")
		)
		(fp_line
			(start 0.12065 -0.3048)
			(end 0.67945 -0.3048)
			(stroke
				(width 0.1)
				(type default)
			)
			(layer "F.Fab")
		)
		(fp_line
			(start 0.12065 -0.2794)
			(end 0.12065 -0.3048)
			(stroke
				(width 0.1)
				(type default)
			)
			(layer "F.Fab")
		)
		(fp_line
			(start 0.67945 -0.3048)
			(end 0.67945 0.3048)
			(stroke
				(width 0.1)
				(type default)
			)
			(layer "F.Fab")
		)
		(fp_line
			(start 0.67945 0.3048)
			(end 0.120396 0.3048)
			(stroke
				(width 0.1)
				(type default)
			)
			(layer "F.Fab")
		)
		(pad "1" smd circle
			(at -0.40005 0)
			(size 0 0)
			(layers "F.Cu" "F.Mask" "F.Paste")
			(net "P3V3_AUX")
		)
		(pad "2" smd circle
			(at 0.40005 0)
			(size 0 0)
			(layers "F.Cu" "F.Mask" "F.Paste")
			(net "GND")
		)
	)
	(footprint ""
		(layer "F.Cu")
		(at 358.297988 -409.388818 90)
		(property "Reference" "R3063"
			(at 0 0 90)
			(layer "F.SilkS")
			(hide yes)
			(effects
				(font
					(size 1.27 1.27)
				)
			)
		)
		(property "Value" ""
			(at 0 0 90)
			(layer "F.Fab")
			(effects
				(font
					(size 1.27 1.27)
				)
			)
		)
		(duplicate_pad_numbers_are_jumpers no)
		(fp_line
			(start 0.7874 -0.4064)
			(end 0.7874 0.4064)
			(stroke
				(width 0.1524)
				(type default)
			)
			(layer "F.SilkS")
		)
		(fp_line
			(start -0.7874 -0.4064)
			(end 0.7874 -0.4064)
			(stroke
				(width 0.1524)
				(type default)
			)
			(layer "F.SilkS")
		)
		(fp_line
			(start 0.7874 0.4064)
			(end -0.7874 0.4064)
			(stroke
				(width 0.1524)
				(type default)
			)
			(layer "F.SilkS")
		)
		(fp_line
			(start -0.7874 0.4064)
			(end -0.7874 -0.4064)
			(stroke
				(width 0.1524)
				(type default)
			)
			(layer "F.SilkS")
		)
		(fp_line
			(start -0.12065 -0.305054)
			(end -0.12065 -0.2794)
			(stroke
				(width 0.1)
				(type default)
			)
			(layer "F.Fab")
		)
		(fp_line
			(start -0.67945 -0.305054)
			(end -0.12065 -0.305054)
			(stroke
				(width 0.1)
				(type default)
			)
			(layer "F.Fab")
		)
		(fp_line
			(start 0.67945 -0.3048)
			(end 0.67945 0.3048)
			(stroke
				(width 0.1)
				(type default)
			)
			(layer "F.Fab")
		)
		(fp_line
			(start 0.12065 -0.3048)
			(end 0.67945 -0.3048)
			(stroke
				(width 0.1)
				(type default)
			)
			(layer "F.Fab")
		)
		(fp_line
			(start 0.12065 -0.2794)
			(end 0.12065 -0.3048)
			(stroke
				(width 0.1)
				(type default)
			)
			(layer "F.Fab")
		)
		(fp_line
			(start -0.12065 -0.2794)
			(end 0.12065 -0.2794)
			(stroke
				(width 0.1)
				(type default)
			)
			(layer "F.Fab")
		)
		(fp_line
			(start 0.120396 0.2794)
			(end -0.12065 0.2794)
			(stroke
				(width 0.1)
				(type default)
			)
			(layer "F.Fab")
		)
		(fp_line
			(start -0.12065 0.2794)
			(end -0.12065 0.3048)
			(stroke
				(width 0.1)
				(type default)
			)
			(layer "F.Fab")
		)
		(fp_line
			(start 0.67945 0.3048)
			(end 0.120396 0.3048)
			(stroke
				(width 0.1)
				(type default)
			)
			(layer "F.Fab")
		)
		(fp_line
			(start 0.120396 0.3048)
			(end 0.120396 0.2794)
			(stroke
				(width 0.1)
				(type default)
			)
			(layer "F.Fab")
		)
		(fp_line
			(start -0.12065 0.3048)
			(end -0.67945 0.3048)
			(stroke
				(width 0.1)
				(type default)
			)
			(layer "F.Fab")
		)
		(fp_line
			(start -0.67945 0.3048)
			(end -0.67945 -0.305054)
			(stroke
				(width 0.1)
				(type default)
			)
			(layer "F.Fab")
		)
		(pad "1" smd circle
			(at -0.40005 0 90)
			(size 0 0)
			(layers "F.Cu" "F.Mask" "F.Paste")
			(net "FM_PDB_BUF_EN_R1")
		)
		(pad "2" smd circle
			(at 0.40005 0 90)
			(size 0 0)
			(layers "F.Cu" "F.Mask" "F.Paste")
			(net "FM_UART_EN")
		)
	)
	(footprint ""
		(layer "F.Cu")
		(at 179.959 -137.632948 -90)
		(property "Reference" "R371"
			(at 0 0 270)
			(layer "F.SilkS")
			(hide yes)
			(effects
				(font
					(size 1.27 1.27)
				)
			)
		)
		(property "Value" ""
			(at 0 0 270)
			(layer "F.Fab")
			(effects
				(font
					(size 1.27 1.27)
				)
			)
		)
		(duplicate_pad_numbers_are_jumpers no)
		(fp_line
			(start -0.7874 0.4064)
			(end -0.7874 -0.4064)
			(stroke
				(width 0.1524)
				(type default)
			)
			(layer "F.SilkS")
		)
		(fp_line
			(start 0.7874 0.4064)
			(end -0.7874 0.4064)
			(stroke
				(width 0.1524)
				(type default)
			)
			(layer "F.SilkS")
		)
		(fp_line
			(start -0.7874 -0.4064)
			(end 0.7874 -0.4064)
			(stroke
				(width 0.1524)
				(type default)
			)
			(layer "F.SilkS")
		)
		(fp_line
			(start 0.7874 -0.4064)
			(end 0.7874 0.4064)
			(stroke
				(width 0.1524)
				(type default)
			)
			(layer "F.SilkS")
		)
		(fp_line
			(start -0.67945 0.3048)
			(end -0.67945 -0.305054)
			(stroke
				(width 0.1)
				(type default)
			)
			(layer "F.Fab")
		)
		(fp_line
			(start -0.12065 0.3048)
			(end -0.67945 0.3048)
			(stroke
				(width 0.1)
				(type default)
			)
			(layer "F.Fab")
		)
		(fp_line
			(start 0.120396 0.3048)
			(end 0.120396 0.2794)
			(stroke
				(width 0.1)
				(type default)
			)
			(layer "F.Fab")
		)
		(fp_line
			(start 0.67945 0.3048)
			(end 0.120396 0.3048)
			(stroke
				(width 0.1)
				(type default)
			)
			(layer "F.Fab")
		)
		(fp_line
			(start -0.12065 0.2794)
			(end -0.12065 0.3048)
			(stroke
				(width 0.1)
				(type default)
			)
			(layer "F.Fab")
		)
		(fp_line
			(start 0.120396 0.2794)
			(end -0.12065 0.2794)
			(stroke
				(width 0.1)
				(type default)
			)
			(layer "F.Fab")
		)
		(fp_line
			(start -0.12065 -0.2794)
			(end 0.12065 -0.2794)
			(stroke
				(width 0.1)
				(type default)
			)
			(layer "F.Fab")
		)
		(fp_line
			(start 0.12065 -0.2794)
			(end 0.12065 -0.3048)
			(stroke
				(width 0.1)
				(type default)
			)
			(layer "F.Fab")
		)
		(fp_line
			(start 0.12065 -0.3048)
			(end 0.67945 -0.3048)
			(stroke
				(width 0.1)
				(type default)
			)
			(layer "F.Fab")
		)
		(fp_line
			(start 0.67945 -0.3048)
			(end 0.67945 0.3048)
			(stroke
				(width 0.1)
				(type default)
			)
			(layer "F.Fab")
		)
		(fp_line
			(start -0.67945 -0.305054)
			(end -0.12065 -0.305054)
			(stroke
				(width 0.1)
				(type default)
			)
			(layer "F.Fab")
		)
		(fp_line
			(start -0.12065 -0.305054)
			(end -0.12065 -0.2794)
			(stroke
				(width 0.1)
				(type default)
			)
			(layer "F.Fab")
		)
		(pad "1" smd circle
			(at -0.40005 0 270)
			(size 0 0)
			(layers "F.Cu" "F.Mask" "F.Paste")
			(net "FPGA_DEBUG_LED_CTRL")
		)
		(pad "2" smd circle
			(at 0.40005 0 270)
			(size 0 0)
			(layers "F.Cu" "F.Mask" "F.Paste")
			(net "FM_FPGA_DEBUG_LED_CTRL")
		)
	)
	(footprint ""
		(layer "F.Cu")
		(at 103.495348 -382.6764 180)
		(property "Reference" "R795"
			(at 0 0 180)
			(layer "F.SilkS")
			(hide yes)
			(effects
				(font
					(size 1.27 1.27)
				)
			)
		)
		(property "Value" ""
			(at 0 0 180)
			(layer "F.Fab")
			(effects
				(font
					(size 1.27 1.27)
				)
			)
		)
		(duplicate_pad_numbers_are_jumpers no)
		(fp_line
			(start 0.32512 0.175006)
			(end -0.32512 0.175006)
			(stroke
				(width 0.1)
				(type default)
			)
			(layer "F.Fab")
		)
		(fp_line
			(start 0.32512 -0.175006)
			(end 0.32512 0.175006)
			(stroke
				(width 0.1)
				(type default)
			)
			(layer "F.Fab")
		)
		(fp_line
			(start -0.32512 0.175006)
			(end -0.32512 -0.175006)
			(stroke
				(width 0.1)
				(type default)
			)
			(layer "F.Fab")
		)
		(fp_line
			(start -0.32512 -0.175006)
			(end 0.32512 -0.175006)
			(stroke
				(width 0.1)
				(type default)
			)
			(layer "F.Fab")
		)
		(pad "1" smd rect
			(at -0.2667 0 180)
			(size 0.3048 0.381)
			(layers "F.Cu" "F.Mask" "F.Paste")
			(net "P1V8_CPU1_RT_1D")
		)
		(pad "2" smd rect
			(at 0.2667 0)
			(size 0.3048 0.381)
			(layers "F.Cu" "F.Mask" "F.Paste")
			(net "RT_CPU1_P1_ADDR1")
		)
	)
	(footprint ""
		(layer "F.Cu")
		(at 24.917654 -346.719398 -90)
		(property "Reference" "PC618_IOP1_4"
			(at 0 0 270)
			(layer "F.SilkS")
			(hide yes)
			(effects
				(font
					(size 1.27 1.27)
				)
			)
		)
		(property "Value" ""
			(at 0 0 270)
			(layer "F.Fab")
			(effects
				(font
					(size 1.27 1.27)
				)
			)
		)
		(duplicate_pad_numbers_are_jumpers no)
		(fp_line
			(start -0.7874 0.4064)
			(end -0.7874 -0.4064)
			(stroke
				(width 0.1524)
				(type default)
			)
			(layer "F.SilkS")
		)
		(fp_line
			(start 0.7874 0.4064)
			(end -0.7874 0.4064)
			(stroke
				(width 0.1524)
				(type default)
			)
			(layer "F.SilkS")
		)
		(fp_line
			(start -0.7874 -0.4064)
			(end 0.7874 -0.4064)
			(stroke
				(width 0.1524)
				(type default)
			)
			(layer "F.SilkS")
		)
		(fp_line
			(start 0.7874 -0.4064)
			(end 0.7874 0.4064)
			(stroke
				(width 0.1524)
				(type default)
			)
			(layer "F.SilkS")
		)
		(fp_line
			(start -0.67945 0.3048)
			(end -0.67945 -0.305054)
			(stroke
				(width 0.1)
				(type default)
			)
			(layer "F.Fab")
		)
		(fp_line
			(start -0.12065 0.3048)
			(end -0.67945 0.3048)
			(stroke
				(width 0.1)
				(type default)
			)
			(layer "F.Fab")
		)
		(fp_line
			(start 0.120396 0.3048)
			(end 0.120396 0.2794)
			(stroke
				(width 0.1)
				(type default)
			)
			(layer "F.Fab")
		)
		(fp_line
			(start 0.67945 0.3048)
			(end 0.120396 0.3048)
			(stroke
				(width 0.1)
				(type default)
			)
			(layer "F.Fab")
		)
		(fp_line
			(start -0.12065 0.2794)
			(end -0.12065 0.3048)
			(stroke
				(width 0.1)
				(type default)
			)
			(layer "F.Fab")
		)
		(fp_line
			(start 0.120396 0.2794)
			(end -0.12065 0.2794)
			(stroke
				(width 0.1)
				(type default)
			)
			(layer "F.Fab")
		)
		(fp_line
			(start -0.12065 -0.2794)
			(end 0.12065 -0.2794)
			(stroke
				(width 0.1)
				(type default)
			)
			(layer "F.Fab")
		)
		(fp_line
			(start 0.12065 -0.2794)
			(end 0.12065 -0.3048)
			(stroke
				(width 0.1)
				(type default)
			)
			(layer "F.Fab")
		)
		(fp_line
			(start 0.12065 -0.3048)
			(end 0.67945 -0.3048)
			(stroke
				(width 0.1)
				(type default)
			)
			(layer "F.Fab")
		)
		(fp_line
			(start 0.67945 -0.3048)
			(end 0.67945 0.3048)
			(stroke
				(width 0.1)
				(type default)
			)
			(layer "F.Fab")
		)
		(fp_line
			(start -0.67945 -0.305054)
			(end -0.12065 -0.305054)
			(stroke
				(width 0.1)
				(type default)
			)
			(layer "F.Fab")
		)
		(fp_line
			(start -0.12065 -0.305054)
			(end -0.12065 -0.2794)
			(stroke
				(width 0.1)
				(type default)
			)
			(layer "F.Fab")
		)
		(pad "1" smd circle
			(at -0.40005 0 270)
			(size 0 0)
			(layers "F.Cu" "F.Mask" "F.Paste")
			(net "PVDDCR_CPU1_P1_PVCC")
		)
		(pad "2" smd circle
			(at 0.40005 0 270)
			(size 0 0)
			(layers "F.Cu" "F.Mask" "F.Paste")
			(net "GND")
		)
	)
	(footprint ""
		(layer "F.Cu")
		(at 83.157314 -138.562334)
		(property "Reference" "R703"
			(at 0 0 0)
			(layer "F.SilkS")
			(hide yes)
			(effects
				(font
					(size 1.27 1.27)
				)
			)
		)
		(property "Value" ""
			(at 0 0 0)
			(layer "F.Fab")
			(effects
				(font
					(size 1.27 1.27)
				)
			)
		)
		(duplicate_pad_numbers_are_jumpers no)
		(fp_line
			(start -0.7874 -0.4064)
			(end 0.7874 -0.4064)
			(stroke
				(width 0.1524)
				(type default)
			)
			(layer "F.SilkS")
		)
		(fp_line
			(start -0.7874 0.4064)
			(end -0.7874 -0.4064)
			(stroke
				(width 0.1524)
				(type default)
			)
			(layer "F.SilkS")
		)
		(fp_line
			(start 0.7874 -0.4064)
			(end 0.7874 0.4064)
			(stroke
				(width 0.1524)
				(type default)
			)
			(layer "F.SilkS")
		)
		(fp_line
			(start 0.7874 0.4064)
			(end -0.7874 0.4064)
			(stroke
				(width 0.1524)
				(type default)
			)
			(layer "F.SilkS")
		)
		(fp_line
			(start -0.67945 -0.305054)
			(end -0.12065 -0.305054)
			(stroke
				(width 0.1)
				(type default)
			)
			(layer "F.Fab")
		)
		(fp_line
			(start -0.67945 0.3048)
			(end -0.67945 -0.305054)
			(stroke
				(width 0.1)
				(type default)
			)
			(layer "F.Fab")
		)
		(fp_line
			(start -0.12065 -0.305054)
			(end -0.12065 -0.2794)
			(stroke
				(width 0.1)
				(type default)
			)
			(layer "F.Fab")
		)
		(fp_line
			(start -0.12065 -0.2794)
			(end 0.12065 -0.2794)
			(stroke
				(width 0.1)
				(type default)
			)
			(layer "F.Fab")
		)
		(fp_line
			(start -0.12065 0.2794)
			(end -0.12065 0.3048)
			(stroke
				(width 0.1)
				(type default)
			)
			(layer "F.Fab")
		)
		(fp_line
			(start -0.12065 0.3048)
			(end -0.67945 0.3048)
			(stroke
				(width 0.1)
				(type default)
			)
			(layer "F.Fab")
		)
		(fp_line
			(start 0.120396 0.2794)
			(end -0.12065 0.2794)
			(stroke
				(width 0.1)
				(type default)
			)
			(layer "F.Fab")
		)
		(fp_line
			(start 0.120396 0.3048)
			(end 0.120396 0.2794)
			(stroke
				(width 0.1)
				(type default)
			)
			(layer "F.Fab")
		)
		(fp_line
			(start 0.12065 -0.3048)
			(end 0.67945 -0.3048)
			(stroke
				(width 0.1)
				(type default)
			)
			(layer "F.Fab")
		)
		(fp_line
			(start 0.12065 -0.2794)
			(end 0.12065 -0.3048)
			(stroke
				(width 0.1)
				(type default)
			)
			(layer "F.Fab")
		)
		(fp_line
			(start 0.67945 -0.3048)
			(end 0.67945 0.3048)
			(stroke
				(width 0.1)
				(type default)
			)
			(layer "F.Fab")
		)
		(fp_line
			(start 0.67945 0.3048)
			(end 0.120396 0.3048)
			(stroke
				(width 0.1)
				(type default)
			)
			(layer "F.Fab")
		)
		(pad "1" smd circle
			(at -0.40005 0)
			(size 0 0)
			(layers "F.Cu" "F.Mask" "F.Paste")
			(net "PWRGD_CPU1_PWROK")
		)
		(pad "2" smd circle
			(at 0.40005 0)
			(size 0 0)
			(layers "F.Cu" "F.Mask" "F.Paste")
			(net "GND")
		)
	)
	(footprint ""
		(layer "F.Cu")
		(at 114.299238 -39.40175 -90)
		(property "Reference" "R6286"
			(at 0 0 270)
			(layer "F.SilkS")
			(hide yes)
			(effects
				(font
					(size 1.27 1.27)
				)
			)
		)
		(property "Value" ""
			(at 0 0 270)
			(layer "F.Fab")
			(effects
				(font
					(size 1.27 1.27)
				)
			)
		)
		(duplicate_pad_numbers_are_jumpers no)
		(fp_line
			(start -0.7874 0.4064)
			(end -0.7874 -0.4064)
			(stroke
				(width 0.1524)
				(type default)
			)
			(layer "F.SilkS")
		)
		(fp_line
			(start 0.7874 0.4064)
			(end -0.7874 0.4064)
			(stroke
				(width 0.1524)
				(type default)
			)
			(layer "F.SilkS")
		)
		(fp_line
			(start -0.7874 -0.4064)
			(end 0.7874 -0.4064)
			(stroke
				(width 0.1524)
				(type default)
			)
			(layer "F.SilkS")
		)
		(fp_line
			(start 0.7874 -0.4064)
			(end 0.7874 0.4064)
			(stroke
				(width 0.1524)
				(type default)
			)
			(layer "F.SilkS")
		)
		(fp_line
			(start -0.67945 0.3048)
			(end -0.67945 -0.305054)
			(stroke
				(width 0.1)
				(type default)
			)
			(layer "F.Fab")
		)
		(fp_line
			(start -0.12065 0.3048)
			(end -0.67945 0.3048)
			(stroke
				(width 0.1)
				(type default)
			)
			(layer "F.Fab")
		)
		(fp_line
			(start 0.120396 0.3048)
			(end 0.120396 0.2794)
			(stroke
				(width 0.1)
				(type default)
			)
			(layer "F.Fab")
		)
		(fp_line
			(start 0.67945 0.3048)
			(end 0.120396 0.3048)
			(stroke
				(width 0.1)
				(type default)
			)
			(layer "F.Fab")
		)
		(fp_line
			(start -0.12065 0.2794)
			(end -0.12065 0.3048)
			(stroke
				(width 0.1)
				(type default)
			)
			(layer "F.Fab")
		)
		(fp_line
			(start 0.120396 0.2794)
			(end -0.12065 0.2794)
			(stroke
				(width 0.1)
				(type default)
			)
			(layer "F.Fab")
		)
		(fp_line
			(start -0.12065 -0.2794)
			(end 0.12065 -0.2794)
			(stroke
				(width 0.1)
				(type default)
			)
			(layer "F.Fab")
		)
		(fp_line
			(start 0.12065 -0.2794)
			(end 0.12065 -0.3048)
			(stroke
				(width 0.1)
				(type default)
			)
			(layer "F.Fab")
		)
		(fp_line
			(start 0.12065 -0.3048)
			(end 0.67945 -0.3048)
			(stroke
				(width 0.1)
				(type default)
			)
			(layer "F.Fab")
		)
		(fp_line
			(start 0.67945 -0.3048)
			(end 0.67945 0.3048)
			(stroke
				(width 0.1)
				(type default)
			)
			(layer "F.Fab")
		)
		(fp_line
			(start -0.67945 -0.305054)
			(end -0.12065 -0.305054)
			(stroke
				(width 0.1)
				(type default)
			)
			(layer "F.Fab")
		)
		(fp_line
			(start -0.12065 -0.305054)
			(end -0.12065 -0.2794)
			(stroke
				(width 0.1)
				(type default)
			)
			(layer "F.Fab")
		)
		(pad "1" smd circle
			(at -0.40005 0 270)
			(size 0 0)
			(layers "F.Cu" "F.Mask" "F.Paste")
			(net "USB_HUB2_MRP_VBUS_DET")
		)
		(pad "2" smd circle
			(at 0.40005 0 270)
			(size 0 0)
			(layers "F.Cu" "F.Mask" "F.Paste")
			(net "USB_HUB2_TI_PWRCTL_POL_MRP_VBUS_DET")
		)
	)
)
